(kicad_pcb
	(version 20260206)
	(generator "pcbnew")
	(generator_version "10.0")
	(general
		(thickness 1.6)
		(legacy_teardrops no)
	)
	(paper "A4")
	(title_block
		(title "03242023_DA0F0TMBIJ0_F0T_Motherboard_J_brd_V01_OCP.brd")
		(comment 1 "Grand Teton / footprints 1321-1326 of 6105")
	)
	(layers
		(0 "F.Cu" signal "TOP")
		(4 "In1.Cu" signal "GND")
		(6 "In2.Cu" signal "IN1")
		(8 "In3.Cu" signal "GND1")
		(10 "In4.Cu" signal "IN2")
		(12 "In5.Cu" signal "GND2")
		(14 "In6.Cu" signal "IN3")
		(16 "In7.Cu" signal "GND3")
		(18 "In8.Cu" signal "VCC")
		(20 "In9.Cu" signal "VCC1")
		(22 "In10.Cu" signal "GND4")
		(24 "In11.Cu" signal "IN4")
		(26 "In12.Cu" signal "GND5")
		(28 "In13.Cu" signal "IN5")
		(30 "In14.Cu" signal "GND6")
		(32 "In15.Cu" signal "IN6")
		(34 "In16.Cu" signal "GND7")
		(2 "B.Cu" signal "BOTTOM")
		(9 "F.Adhes" user "F.Adhesive")
		(11 "B.Adhes" user "B.Adhesive")
		(13 "F.Paste" user "Package Geometry/Pastemask Top")
		(15 "B.Paste" user "Package Geometry/Pastemask Bottom")
		(5 "F.SilkS" user "Ref Des/Silkscreen Top")
		(7 "B.SilkS" user "Ref Des/Silkscreen Bottom")
		(1 "F.Mask" user "Board Geometry/Soldermask Top")
		(3 "B.Mask" user "Board Geometry/Soldermask Bottom")
		(17 "Dwgs.User" user "User.Drawings")
		(19 "Cmts.User" user "User.Comments")
		(21 "Eco1.User" user "User.Eco1")
		(23 "Eco2.User" user "User.Eco2")
		(25 "Edge.Cuts" user "Board Geometry/Outline")
		(27 "Margin" user)
		(31 "F.CrtYd" user "Package Geometry/Place Bound Top")
		(29 "B.CrtYd" user "Package Geometry/Place Bound Bottom")
		(35 "F.Fab" user "Ref Des/Assembly Top")
		(33 "B.Fab" user "Ref Des/Assembly Bottom")
	)
	(footprint ""
		(layer "F.Cu")
		(at 262.401558 -394.17117)
		(property "Reference" "PR2529"
			(at 0 0 0)
			(layer "F.SilkS")
			(hide yes)
			(effects
				(font
					(size 1.27 1.27)
				)
			)
		)
		(property "Value" ""
			(at 0 0 0)
			(layer "F.Fab")
			(effects
				(font
					(size 1.27 1.27)
				)
			)
		)
		(duplicate_pad_numbers_are_jumpers no)
		(fp_line
			(start -0.7874 -0.4064)
			(end 0.7874 -0.4064)
			(stroke
				(width 0.1524)
				(type default)
			)
			(layer "F.SilkS")
		)
		(fp_line
			(start -0.7874 0.4064)
			(end -0.7874 -0.4064)
			(stroke
				(width 0.1524)
				(type default)
			)
			(layer "F.SilkS")
		)
		(fp_line
			(start 0.7874 -0.4064)
			(end 0.7874 0.4064)
			(stroke
				(width 0.1524)
				(type default)
			)
			(layer "F.SilkS")
		)
		(fp_line
			(start 0.7874 0.4064)
			(end -0.7874 0.4064)
			(stroke
				(width 0.1524)
				(type default)
			)
			(layer "F.SilkS")
		)
		(fp_line
			(start -0.67945 -0.305054)
			(end -0.12065 -0.305054)
			(stroke
				(width 0.1)
				(type default)
			)
			(layer "F.Fab")
		)
		(fp_line
			(start -0.67945 0.3048)
			(end -0.67945 -0.305054)
			(stroke
				(width 0.1)
				(type default)
			)
			(layer "F.Fab")
		)
		(fp_line
			(start -0.12065 -0.305054)
			(end -0.12065 -0.2794)
			(stroke
				(width 0.1)
				(type default)
			)
			(layer "F.Fab")
		)
		(fp_line
			(start -0.12065 -0.2794)
			(end 0.12065 -0.2794)
			(stroke
				(width 0.1)
				(type default)
			)
			(layer "F.Fab")
		)
		(fp_line
			(start -0.12065 0.2794)
			(end -0.12065 0.3048)
			(stroke
				(width 0.1)
				(type default)
			)
			(layer "F.Fab")
		)
		(fp_line
			(start -0.12065 0.3048)
			(end -0.67945 0.3048)
			(stroke
				(width 0.1)
				(type default)
			)
			(layer "F.Fab")
		)
		(fp_line
			(start 0.120396 0.2794)
			(end -0.12065 0.2794)
			(stroke
				(width 0.1)
				(type default)
			)
			(layer "F.Fab")
		)
		(fp_line
			(start 0.120396 0.3048)
			(end 0.120396 0.2794)
			(stroke
				(width 0.1)
				(type default)
			)
			(layer "F.Fab")
		)
		(fp_line
			(start 0.12065 -0.3048)
			(end 0.67945 -0.3048)
			(stroke
				(width 0.1)
				(type default)
			)
			(layer "F.Fab")
		)
		(fp_line
			(start 0.12065 -0.2794)
			(end 0.12065 -0.3048)
			(stroke
				(width 0.1)
				(type default)
			)
			(layer "F.Fab")
		)
		(fp_line
			(start 0.67945 -0.3048)
			(end 0.67945 0.3048)
			(stroke
				(width 0.1)
				(type default)
			)
			(layer "F.Fab")
		)
		(fp_line
			(start 0.67945 0.3048)
			(end 0.120396 0.3048)
			(stroke
				(width 0.1)
				(type default)
			)
			(layer "F.Fab")
		)
		(pad "1" smd circle
			(at -0.40005 0)
			(size 0 0)
			(layers "F.Cu" "F.Mask" "F.Paste")
			(net "P12V_HSC_GATE_G2")
		)
		(pad "2" smd circle
			(at 0.40005 0)
			(size 0 0)
			(layers "F.Cu" "F.Mask" "F.Paste")
			(net "P12V_HSC_GATE2")
		)
	)
	(footprint ""
		(layer "F.Cu")
		(at 520.044426 -148.123148 90)
		(property "Reference" "X19"
			(at -3.511804 2.541524 90)
			(unlocked yes)
			(layer "F.SilkS")
			(effects
				(font
					(size 0.7874 0.5842)
					(thickness 0.1524)
				)
				(justify left)
			)
		)
		(property "Value" ""
			(at 0 0 90)
			(layer "F.Fab")
			(effects
				(font
					(size 1.27 1.27)
				)
			)
		)
		(property "Device Type" "TP_TDR_4P_FTS_MPKT4_H025P0200_I"
			(at 1.30175 1.27 180)
			(unlocked yes)
			(layer "F.Fab")
			(hide yes)
			(effects
				(font
					(size 0.635 0.4064)
					(thickness 0.1524)
				)
			)
		)
		(property "User Part Number" "TP15"
			(at 1.30175 1.27 180)
			(unlocked yes)
			(layer "Cmts.User")
			(hide yes)
			(effects
				(font
					(size 0.635 0.4064)
					(thickness 0.1524)
				)
			)
		)
		(duplicate_pad_numbers_are_jumpers no)
		(fp_line
			(start 2.54 -1.27)
			(end 0 -1.27)
			(stroke
				(width 0.1524)
				(type default)
			)
			(layer "F.SilkS")
		)
		(fp_line
			(start 0 -1.27)
			(end 0 -0.635)
			(stroke
				(width 0.1524)
				(type default)
			)
			(layer "F.SilkS")
		)
		(fp_line
			(start 2.54 -1.1303)
			(end 2.54 -1.27)
			(stroke
				(width 0.1524)
				(type default)
			)
			(layer "F.SilkS")
		)
		(fp_line
			(start 0 0.635)
			(end 0 1.905)
			(stroke
				(width 0.1524)
				(type default)
			)
			(layer "F.SilkS")
		)
		(fp_line
			(start 2.54 1.4097)
			(end 2.54 1.1303)
			(stroke
				(width 0.1524)
				(type default)
			)
			(layer "F.SilkS")
		)
		(fp_line
			(start 0 3.175)
			(end 0 3.81)
			(stroke
				(width 0.1524)
				(type default)
			)
			(layer "F.SilkS")
		)
		(fp_line
			(start 2.54 3.81)
			(end 2.54 3.6703)
			(stroke
				(width 0.1524)
				(type default)
			)
			(layer "F.SilkS")
		)
		(fp_line
			(start 0 3.81)
			(end 2.54 3.81)
			(stroke
				(width 0.1524)
				(type default)
			)
			(layer "F.SilkS")
		)
		(fp_poly
			(pts
				(xy -1.330706 0) (xy -2.854706 0.762) (xy -2.854706 -0.762)
			)
			(stroke
				(width 0)
				(type default)
			)
			(fill yes)
			(layer "F.SilkS")
		)
		(fp_line
			(start 2.54 -1.27)
			(end 0 -1.27)
			(stroke
				(width 0.1)
				(type default)
			)
			(layer "F.Fab")
		)
		(fp_line
			(start 0 -1.27)
			(end 0 3.81)
			(stroke
				(width 0.1)
				(type default)
			)
			(layer "F.Fab")
		)
		(fp_line
			(start 2.54 3.81)
			(end 2.54 -1.27)
			(stroke
				(width 0.1)
				(type default)
			)
			(layer "F.Fab")
		)
		(fp_line
			(start 0 3.81)
			(end 2.54 3.81)
			(stroke
				(width 0.1)
				(type default)
			)
			(layer "F.Fab")
		)
		(fp_poly
			(pts
				(xy -0.761746 0) (xy -2.285746 -0.762) (xy -2.285746 0.762)
			)
			(stroke
				(width 0)
				(type default)
			)
			(fill yes)
			(layer "F.Fab")
		)
		(pad "1" thru_hole circle
			(at 0 0 90)
			(size 1.0033 1.0033)
			(drill 0.249936)
			(layers "*.Cu" "*.Mask")
			(remove_unused_layers no)
			(net "TDR_DIFF_100_TOP_DN")
			(clearance 0.10795)
			(thermal_gap 0.10795)
			(padstack
				(mode front_inner_back)
				(layer "Inner"
					(shape circle)
					(size 0.8001 0.8001)
					(clearance 0.1524)
				)
				(layer "B.Cu"
					(shape circle)
					(size 1.0033 1.0033)
					(clearance 0.10795)
				)
			)
		)
		(pad "2" thru_hole circle
			(at 2.54 0 90)
			(size 1.9939 1.9939)
			(drill 0.249936)
			(layers "*.Cu" "*.Mask")
			(remove_unused_layers no)
			(net "T1_GND")
			(clearance 0.10795)
			(thermal_gap 0.10795)
			(padstack
				(mode front_inner_back)
				(layer "Inner"
					(shape circle)
					(size 0.8001 0.8001)
					(clearance 0.1524)
				)
				(layer "B.Cu"
					(shape circle)
					(size 1.9939 1.9939)
					(clearance 0.10795)
				)
			)
		)
		(pad "3" thru_hole circle
			(at 2.54 2.54 90)
			(size 1.9939 1.9939)
			(drill 0.249936)
			(layers "*.Cu" "*.Mask")
			(remove_unused_layers no)
			(net "T1_GND")
			(clearance 0.10795)
			(thermal_gap 0.10795)
			(padstack
				(mode front_inner_back)
				(layer "Inner"
					(shape circle)
					(size 0.8001 0.8001)
					(clearance 0.1524)
				)
				(layer "B.Cu"
					(shape circle)
					(size 1.9939 1.9939)
					(clearance 0.10795)
				)
			)
		)
		(pad "4" thru_hole circle
			(at 0 2.54 90)
			(size 1.0033 1.0033)
			(drill 0.249936)
			(layers "*.Cu" "*.Mask")
			(remove_unused_layers no)
			(net "TDR_DIFF_100_TOP_DP")
			(clearance 0.10795)
			(thermal_gap 0.10795)
			(padstack
				(mode front_inner_back)
				(layer "Inner"
					(shape circle)
					(size 0.8001 0.8001)
					(clearance 0.1524)
				)
				(layer "B.Cu"
					(shape circle)
					(size 1.0033 1.0033)
					(clearance 0.10795)
				)
			)
		)
	)
	(footprint ""
		(layer "F.Cu")
		(at 369.368578 -413.90951 -90)
		(property "Reference" "R4191"
			(at 0 0 270)
			(layer "F.SilkS")
			(hide yes)
			(effects
				(font
					(size 1.27 1.27)
				)
			)
		)
		(property "Value" ""
			(at 0 0 270)
			(layer "F.Fab")
			(effects
				(font
					(size 1.27 1.27)
				)
			)
		)
		(duplicate_pad_numbers_are_jumpers no)
		(fp_line
			(start -0.7874 0.4064)
			(end -0.7874 -0.4064)
			(stroke
				(width 0.1524)
				(type default)
			)
			(layer "F.SilkS")
		)
		(fp_line
			(start 0.7874 0.4064)
			(end -0.7874 0.4064)
			(stroke
				(width 0.1524)
				(type default)
			)
			(layer "F.SilkS")
		)
		(fp_line
			(start -0.7874 -0.4064)
			(end 0.7874 -0.4064)
			(stroke
				(width 0.1524)
				(type default)
			)
			(layer "F.SilkS")
		)
		(fp_line
			(start 0.7874 -0.4064)
			(end 0.7874 0.4064)
			(stroke
				(width 0.1524)
				(type default)
			)
			(layer "F.SilkS")
		)
		(fp_line
			(start -0.67945 0.3048)
			(end -0.67945 -0.305054)
			(stroke
				(width 0.1)
				(type default)
			)
			(layer "F.Fab")
		)
		(fp_line
			(start -0.12065 0.3048)
			(end -0.67945 0.3048)
			(stroke
				(width 0.1)
				(type default)
			)
			(layer "F.Fab")
		)
		(fp_line
			(start 0.120396 0.3048)
			(end 0.120396 0.2794)
			(stroke
				(width 0.1)
				(type default)
			)
			(layer "F.Fab")
		)
		(fp_line
			(start 0.67945 0.3048)
			(end 0.120396 0.3048)
			(stroke
				(width 0.1)
				(type default)
			)
			(layer "F.Fab")
		)
		(fp_line
			(start -0.12065 0.2794)
			(end -0.12065 0.3048)
			(stroke
				(width 0.1)
				(type default)
			)
			(layer "F.Fab")
		)
		(fp_line
			(start 0.120396 0.2794)
			(end -0.12065 0.2794)
			(stroke
				(width 0.1)
				(type default)
			)
			(layer "F.Fab")
		)
		(fp_line
			(start -0.12065 -0.2794)
			(end 0.12065 -0.2794)
			(stroke
				(width 0.1)
				(type default)
			)
			(layer "F.Fab")
		)
		(fp_line
			(start 0.12065 -0.2794)
			(end 0.12065 -0.3048)
			(stroke
				(width 0.1)
				(type default)
			)
			(layer "F.Fab")
		)
		(fp_line
			(start 0.12065 -0.3048)
			(end 0.67945 -0.3048)
			(stroke
				(width 0.1)
				(type default)
			)
			(layer "F.Fab")
		)
		(fp_line
			(start 0.67945 -0.3048)
			(end 0.67945 0.3048)
			(stroke
				(width 0.1)
				(type default)
			)
			(layer "F.Fab")
		)
		(fp_line
			(start -0.67945 -0.305054)
			(end -0.12065 -0.305054)
			(stroke
				(width 0.1)
				(type default)
			)
			(layer "F.Fab")
		)
		(fp_line
			(start -0.12065 -0.305054)
			(end -0.12065 -0.2794)
			(stroke
				(width 0.1)
				(type default)
			)
			(layer "F.Fab")
		)
		(pad "1" smd circle
			(at -0.40005 0 270)
			(size 0 0)
			(layers "F.Cu" "F.Mask" "F.Paste")
			(net "U270_0_ADD2")
		)
		(pad "2" smd circle
			(at 0.40005 0 270)
			(size 0 0)
			(layers "F.Cu" "F.Mask" "F.Paste")
			(net "GND")
		)
	)
	(footprint ""
		(layer "F.Cu")
		(at 201.00036 -114.264948 180)
		(property "Reference" "R4146"
			(at 0 0 180)
			(layer "F.SilkS")
			(hide yes)
			(effects
				(font
					(size 1.27 1.27)
				)
			)
		)
		(property "Value" ""
			(at 0 0 180)
			(layer "F.Fab")
			(effects
				(font
					(size 1.27 1.27)
				)
			)
		)
		(duplicate_pad_numbers_are_jumpers no)
		(fp_line
			(start 0.7874 0.4064)
			(end -0.7874 0.4064)
			(stroke
				(width 0.1524)
				(type default)
			)
			(layer "F.SilkS")
		)
		(fp_line
			(start 0.7874 -0.4064)
			(end 0.7874 0.4064)
			(stroke
				(width 0.1524)
				(type default)
			)
			(layer "F.SilkS")
		)
		(fp_line
			(start -0.7874 0.4064)
			(end -0.7874 -0.4064)
			(stroke
				(width 0.1524)
				(type default)
			)
			(layer "F.SilkS")
		)
		(fp_line
			(start -0.7874 -0.4064)
			(end 0.7874 -0.4064)
			(stroke
				(width 0.1524)
				(type default)
			)
			(layer "F.SilkS")
		)
		(fp_line
			(start 0.67945 0.3048)
			(end 0.120396 0.3048)
			(stroke
				(width 0.1)
				(type default)
			)
			(layer "F.Fab")
		)
		(fp_line
			(start 0.67945 -0.3048)
			(end 0.67945 0.3048)
			(stroke
				(width 0.1)
				(type default)
			)
			(layer "F.Fab")
		)
		(fp_line
			(start 0.12065 -0.2794)
			(end 0.12065 -0.3048)
			(stroke
				(width 0.1)
				(type default)
			)
			(layer "F.Fab")
		)
		(fp_line
			(start 0.12065 -0.3048)
			(end 0.67945 -0.3048)
			(stroke
				(width 0.1)
				(type default)
			)
			(layer "F.Fab")
		)
		(fp_line
			(start 0.120396 0.3048)
			(end 0.120396 0.2794)
			(stroke
				(width 0.1)
				(type default)
			)
			(layer "F.Fab")
		)
		(fp_line
			(start 0.120396 0.2794)
			(end -0.12065 0.2794)
			(stroke
				(width 0.1)
				(type default)
			)
			(layer "F.Fab")
		)
		(fp_line
			(start -0.12065 0.3048)
			(end -0.67945 0.3048)
			(stroke
				(width 0.1)
				(type default)
			)
			(layer "F.Fab")
		)
		(fp_line
			(start -0.12065 0.2794)
			(end -0.12065 0.3048)
			(stroke
				(width 0.1)
				(type default)
			)
			(layer "F.Fab")
		)
		(fp_line
			(start -0.12065 -0.2794)
			(end 0.12065 -0.2794)
			(stroke
				(width 0.1)
				(type default)
			)
			(layer "F.Fab")
		)
		(fp_line
			(start -0.12065 -0.305054)
			(end -0.12065 -0.2794)
			(stroke
				(width 0.1)
				(type default)
			)
			(layer "F.Fab")
		)
		(fp_line
			(start -0.67945 0.3048)
			(end -0.67945 -0.305054)
			(stroke
				(width 0.1)
				(type default)
			)
			(layer "F.Fab")
		)
		(fp_line
			(start -0.67945 -0.305054)
			(end -0.12065 -0.305054)
			(stroke
				(width 0.1)
				(type default)
			)
			(layer "F.Fab")
		)
		(pad "1" smd circle
			(at -0.40005 0 180)
			(size 0 0)
			(layers "F.Cu" "F.Mask" "F.Paste")
			(net "GPU_3V3IO_RSVD3_FFU_ISO")
		)
		(pad "2" smd circle
			(at 0.40005 0 180)
			(size 0 0)
			(layers "F.Cu" "F.Mask" "F.Paste")
			(net "GPU_3V3IO_RSVD3_FFU_ISO_R")
		)
	)
	(footprint ""
		(layer "F.Cu")
		(at 203.399898 -22.29993)
		(property "Reference" "H103"
			(at -4.60502 -5.580888 0)
			(unlocked yes)
			(layer "F.SilkS")
			(effects
				(font
					(size 0.7874 0.5842)
					(thickness 0.1524)
				)
				(justify left)
			)
		)
		(property "Value" ""
			(at 0 0 0)
			(layer "F.Fab")
			(effects
				(font
					(size 1.27 1.27)
				)
			)
		)
		(duplicate_pad_numbers_are_jumpers no)
		(pad "1" thru_hole circle
			(at 0 0)
			(size 10.0076 10.0076)
			(drill 5.6134)
			(layers "*.Cu" "*.Mask")
			(remove_unused_layers no)
			(net "GND")
			(clearance -1.9431)
		)
	)
	(footprint ""
		(layer "F.Cu")
		(at 317.396622 -57.775348 180)
		(property "Reference" "R618"
			(at 0 0 180)
			(layer "F.SilkS")
			(hide yes)
			(effects
				(font
					(size 1.27 1.27)
				)
			)
		)
		(property "Value" ""
			(at 0 0 180)
			(layer "F.Fab")
			(effects
				(font
					(size 1.27 1.27)
				)
			)
		)
		(duplicate_pad_numbers_are_jumpers no)
		(fp_line
			(start 0.7874 0.4064)
			(end -0.7874 0.4064)
			(stroke
				(width 0.1524)
				(type default)
			)
			(layer "F.SilkS")
		)
		(fp_line
			(start 0.7874 -0.4064)
			(end 0.7874 0.4064)
			(stroke
				(width 0.1524)
				(type default)
			)
			(layer "F.SilkS")
		)
		(fp_line
			(start -0.7874 0.4064)
			(end -0.7874 -0.4064)
			(stroke
				(width 0.1524)
				(type default)
			)
			(layer "F.SilkS")
		)
		(fp_line
			(start -0.7874 -0.4064)
			(end 0.7874 -0.4064)
			(stroke
				(width 0.1524)
				(type default)
			)
			(layer "F.SilkS")
		)
		(fp_line
			(start 0.67945 0.3048)
			(end 0.120396 0.3048)
			(stroke
				(width 0.1)
				(type default)
			)
			(layer "F.Fab")
		)
		(fp_line
			(start 0.67945 -0.3048)
			(end 0.67945 0.3048)
			(stroke
				(width 0.1)
				(type default)
			)
			(layer "F.Fab")
		)
		(fp_line
			(start 0.12065 -0.2794)
			(end 0.12065 -0.3048)
			(stroke
				(width 0.1)
				(type default)
			)
			(layer "F.Fab")
		)
		(fp_line
			(start 0.12065 -0.3048)
			(end 0.67945 -0.3048)
			(stroke
				(width 0.1)
				(type default)
			)
			(layer "F.Fab")
		)
		(fp_line
			(start 0.120396 0.3048)
			(end 0.120396 0.2794)
			(stroke
				(width 0.1)
				(type default)
			)
			(layer "F.Fab")
		)
		(fp_line
			(start 0.120396 0.2794)
			(end -0.12065 0.2794)
			(stroke
				(width 0.1)
				(type default)
			)
			(layer "F.Fab")
		)
		(fp_line
			(start -0.12065 0.3048)
			(end -0.67945 0.3048)
			(stroke
				(width 0.1)
				(type default)
			)
			(layer "F.Fab")
		)
		(fp_line
			(start -0.12065 0.2794)
			(end -0.12065 0.3048)
			(stroke
				(width 0.1)
				(type default)
			)
			(layer "F.Fab")
		)
		(fp_line
			(start -0.12065 -0.2794)
			(end 0.12065 -0.2794)
			(stroke
				(width 0.1)
				(type default)
			)
			(layer "F.Fab")
		)
		(fp_line
			(start -0.12065 -0.305054)
			(end -0.12065 -0.2794)
			(stroke
				(width 0.1)
				(type default)
			)
			(layer "F.Fab")
		)
		(fp_line
			(start -0.67945 0.3048)
			(end -0.67945 -0.305054)
			(stroke
				(width 0.1)
				(type default)
			)
			(layer "F.Fab")
		)
		(fp_line
			(start -0.67945 -0.305054)
			(end -0.12065 -0.305054)
			(stroke
				(width 0.1)
				(type default)
			)
			(layer "F.Fab")
		)
		(pad "1" smd circle
			(at -0.40005 0 180)
			(size 0 0)
			(layers "F.Cu" "F.Mask" "F.Paste")
			(net "FM_PCH_IO_EXPANDER")
		)
		(pad "2" smd circle
			(at 0.40005 0 180)
			(size 0 0)
			(layers "F.Cu" "F.Mask" "F.Paste")
			(net "GND")
		)
	)
)
